# S9S_MB_2U (Grand Teton) — schematic netlist excerpt (pin names and nets, part order shuffled) for the footprints in the layout excerpt that follows; sources: Cadence DE-HDL packaged netlist, KiCad conversion of 03242023_DA0F0TMBIJ0_F0T_Motherboard_J_brd_V01_OCP.brd

C998  Q_CAP  10UF 6.3V 20% X6S  pkg C0402  page 74 : A = PVCCIN_CPU0 ; B = GND
C579  Q_CAP  0.1UF 25V 10% X7R  pkg 0402  page 158 : A = P3V3_AUX ; B = GND
C899  Q_CAP_DIFFBUS  DIFF BUS_0.22UF 6.3V 20% X6S  pkg C0201  page 174 : \1\ = P5E_CPU0_PE3_TX_C_DP<1> ; \2\ = P5E_CPU0_PE3_TX_DP<1>

(kicad_pcb
	(version 20260206)
	(generator "pcbnew")
	(generator_version "10.0")
	(general
		(thickness 1.6)
		(legacy_teardrops no)
	)
	(paper "A4")
	(title_block
		(title "03242023_DA0F0TMBIJ0_F0T_Motherboard_J_brd_V01_OCP.brd")
		(comment 1 "Grand Teton / footprints 3865-3867 of 6105")
	)
	(layers
		(0 "F.Cu" signal "TOP")
		(4 "In1.Cu" signal "GND")
		(6 "In2.Cu" signal "IN1")
		(8 "In3.Cu" signal "GND1")
		(10 "In4.Cu" signal "IN2")
		(12 "In5.Cu" signal "GND2")
		(14 "In6.Cu" signal "IN3")
		(16 "In7.Cu" signal "GND3")
		(18 "In8.Cu" signal "VCC")
		(20 "In9.Cu" signal "VCC1")
		(22 "In10.Cu" signal "GND4")
		(24 "In11.Cu" signal "IN4")
		(26 "In12.Cu" signal "GND5")
		(28 "In13.Cu" signal "IN5")
		(30 "In14.Cu" signal "GND6")
		(32 "In15.Cu" signal "IN6")
		(34 "In16.Cu" signal "GND7")
		(2 "B.Cu" signal "BOTTOM")
		(9 "F.Adhes" user "F.Adhesive")
		(11 "B.Adhes" user "B.Adhesive")
		(13 "F.Paste" user "Package Geometry/Pastemask Top")
		(15 "B.Paste" user "Package Geometry/Pastemask Bottom")
		(5 "F.SilkS" user "Ref Des/Silkscreen Top")
		(7 "B.SilkS" user "Ref Des/Silkscreen Bottom")
		(1 "F.Mask" user "Board Geometry/Soldermask Top")
		(3 "B.Mask" user "Board Geometry/Soldermask Bottom")
		(17 "Dwgs.User" user "User.Drawings")
		(19 "Cmts.User" user "User.Comments")
		(21 "Eco1.User" user "User.Eco1")
		(23 "Eco2.User" user "User.Eco2")
		(25 "Edge.Cuts" user "Board Geometry/Outline")
		(27 "Margin" user)
		(31 "F.CrtYd" user "Package Geometry/Place Bound Top")
		(29 "B.CrtYd" user "Package Geometry/Place Bound Bottom")
		(35 "F.Fab" user "Ref Des/Assembly Top")
		(33 "B.Fab" user "Ref Des/Assembly Bottom")
	)
	(footprint ""
		(layer "F.Cu")
		(at 416.54349 -408.517344 -90)
		(property "Reference" "C899"
			(at 0 0 270)
			(layer "F.SilkS")
			(hide yes)
			(effects
				(font
					(size 1.27 1.27)
				)
			)
		)
		(property "Value" ""
			(at 0 0 270)
			(layer "F.Fab")
			(effects
				(font
					(size 1.27 1.27)
				)
			)
		)
		(duplicate_pad_numbers_are_jumpers no)
		(fp_line
			(start -0.299974 0.150114)
			(end -0.299974 -0.150114)
			(stroke
				(width 0.1)
				(type default)
			)
			(layer "F.Fab")
		)
		(fp_line
			(start 0.299974 0.150114)
			(end -0.299974 0.150114)
			(stroke
				(width 0.1)
				(type default)
			)
			(layer "F.Fab")
		)
		(fp_line
			(start -0.299974 -0.150114)
			(end 0.299974 -0.150114)
			(stroke
				(width 0.1)
				(type default)
			)
			(layer "F.Fab")
		)
		(fp_line
			(start 0.299974 -0.150114)
			(end 0.299974 0.150114)
			(stroke
				(width 0.1)
				(type default)
			)
			(layer "F.Fab")
		)
		(pad "1" smd rect
			(at -0.2667 0 270)
			(size 0.3048 0.381)
			(layers "F.Cu" "F.Mask" "F.Paste")
			(net "P5E_CPU0_PE3_TX_C_DP<1>")
		)
		(pad "2" smd rect
			(at 0.2667 0 270)
			(size 0.3048 0.381)
			(layers "F.Cu" "F.Mask" "F.Paste")
			(net "P5E_CPU0_PE3_TX_DP<1>")
		)
	)
	(footprint ""
		(layer "F.Cu")
		(at 352.283014 -252.956314 -90)
		(property "Reference" "C998"
			(at 0 0 270)
			(layer "F.SilkS")
			(hide yes)
			(effects
				(font
					(size 1.27 1.27)
				)
			)
		)
		(property "Value" ""
			(at 0 0 270)
			(layer "F.Fab")
			(effects
				(font
					(size 1.27 1.27)
				)
			)
		)
		(duplicate_pad_numbers_are_jumpers no)
		(fp_line
			(start -0.7874 0.4064)
			(end -0.7874 -0.4064)
			(stroke
				(width 0.1524)
				(type default)
			)
			(layer "F.SilkS")
		)
		(fp_line
			(start 0.7874 0.4064)
			(end -0.7874 0.4064)
			(stroke
				(width 0.1524)
				(type default)
			)
			(layer "F.SilkS")
		)
		(fp_line
			(start -0.7874 -0.4064)
			(end 0.7874 -0.4064)
			(stroke
				(width 0.1524)
				(type default)
			)
			(layer "F.SilkS")
		)
		(fp_line
			(start 0.7874 -0.4064)
			(end 0.7874 0.4064)
			(stroke
				(width 0.1524)
				(type default)
			)
			(layer "F.SilkS")
		)
		(fp_line
			(start -0.67945 0.3048)
			(end -0.67945 -0.305054)
			(stroke
				(width 0.1)
				(type default)
			)
			(layer "F.Fab")
		)
		(fp_line
			(start -0.12065 0.3048)
			(end -0.67945 0.3048)
			(stroke
				(width 0.1)
				(type default)
			)
			(layer "F.Fab")
		)
		(fp_line
			(start 0.120396 0.3048)
			(end 0.120396 0.2794)
			(stroke
				(width 0.1)
				(type default)
			)
			(layer "F.Fab")
		)
		(fp_line
			(start 0.67945 0.3048)
			(end 0.120396 0.3048)
			(stroke
				(width 0.1)
				(type default)
			)
			(layer "F.Fab")
		)
		(fp_line
			(start -0.12065 0.2794)
			(end -0.12065 0.3048)
			(stroke
				(width 0.1)
				(type default)
			)
			(layer "F.Fab")
		)
		(fp_line
			(start 0.120396 0.2794)
			(end -0.12065 0.2794)
			(stroke
				(width 0.1)
				(type default)
			)
			(layer "F.Fab")
		)
		(fp_line
			(start -0.12065 -0.2794)
			(end 0.12065 -0.2794)
			(stroke
				(width 0.1)
				(type default)
			)
			(layer "F.Fab")
		)
		(fp_line
			(start 0.12065 -0.2794)
			(end 0.12065 -0.3048)
			(stroke
				(width 0.1)
				(type default)
			)
			(layer "F.Fab")
		)
		(fp_line
			(start 0.12065 -0.3048)
			(end 0.67945 -0.3048)
			(stroke
				(width 0.1)
				(type default)
			)
			(layer "F.Fab")
		)
		(fp_line
			(start 0.67945 -0.3048)
			(end 0.67945 0.3048)
			(stroke
				(width 0.1)
				(type default)
			)
			(layer "F.Fab")
		)
		(fp_line
			(start -0.67945 -0.305054)
			(end -0.12065 -0.305054)
			(stroke
				(width 0.1)
				(type default)
			)
			(layer "F.Fab")
		)
		(fp_line
			(start -0.12065 -0.305054)
			(end -0.12065 -0.2794)
			(stroke
				(width 0.1)
				(type default)
			)
			(layer "F.Fab")
		)
		(pad "1" smd circle
			(at -0.40005 0 270)
			(size 0 0)
			(layers "F.Cu" "F.Mask" "F.Paste")
			(net "PVCCIN_CPU0")
		)
		(pad "2" smd circle
			(at 0.40005 0 270)
			(size 0 0)
			(layers "F.Cu" "F.Mask" "F.Paste")
			(net "GND")
		)
	)
	(footprint ""
		(layer "F.Cu")
		(at 461.579214 -120.020334)
		(property "Reference" "C579"
			(at 0 0 0)
			(layer "F.SilkS")
			(hide yes)
			(effects
				(font
					(size 1.27 1.27)
				)
			)
		)
		(property "Value" ""
			(at 0 0 0)
			(layer "F.Fab")
			(effects
				(font
					(size 1.27 1.27)
				)
			)
		)
		(duplicate_pad_numbers_are_jumpers no)
		(fp_line
			(start -0.7874 -0.4064)
			(end 0.7874 -0.4064)
			(stroke
				(width 0.1524)
				(type default)
			)
			(layer "F.SilkS")
		)
		(fp_line
			(start -0.7874 0.4064)
			(end -0.7874 -0.4064)
			(stroke
				(width 0.1524)
				(type default)
			)
			(layer "F.SilkS")
		)
		(fp_line
			(start 0.7874 -0.4064)
			(end 0.7874 0.4064)
			(stroke
				(width 0.1524)
				(type default)
			)
			(layer "F.SilkS")
		)
		(fp_line
			(start 0.7874 0.4064)
			(end -0.7874 0.4064)
			(stroke
				(width 0.1524)
				(type default)
			)
			(layer "F.SilkS")
		)
		(fp_line
			(start -0.67945 -0.305054)
			(end -0.12065 -0.305054)
			(stroke
				(width 0.1)
				(type default)
			)
			(layer "F.Fab")
		)
		(fp_line
			(start -0.67945 0.3048)
			(end -0.67945 -0.305054)
			(stroke
				(width 0.1)
				(type default)
			)
			(layer "F.Fab")
		)
		(fp_line
			(start -0.12065 -0.305054)
			(end -0.12065 -0.2794)
			(stroke
				(width 0.1)
				(type default)
			)
			(layer "F.Fab")
		)
		(fp_line
			(start -0.12065 -0.2794)
			(end 0.12065 -0.2794)
			(stroke
				(width 0.1)
				(type default)
			)
			(layer "F.Fab")
		)
		(fp_line
			(start -0.12065 0.2794)
			(end -0.12065 0.3048)
			(stroke
				(width 0.1)
				(type default)
			)
			(layer "F.Fab")
		)
		(fp_line
			(start -0.12065 0.3048)
			(end -0.67945 0.3048)
			(stroke
				(width 0.1)
				(type default)
			)
			(layer "F.Fab")
		)
		(fp_line
			(start 0.120396 0.2794)
			(end -0.12065 0.2794)
			(stroke
				(width 0.1)
				(type default)
			)
			(layer "F.Fab")
		)
		(fp_line
			(start 0.120396 0.3048)
			(end 0.120396 0.2794)
			(stroke
				(width 0.1)
				(type default)
			)
			(layer "F.Fab")
		)
		(fp_line
			(start 0.12065 -0.3048)
			(end 0.67945 -0.3048)
			(stroke
				(width 0.1)
				(type default)
			)
			(layer "F.Fab")
		)
		(fp_line
			(start 0.12065 -0.2794)
			(end 0.12065 -0.3048)
			(stroke
				(width 0.1)
				(type default)
			)
			(layer "F.Fab")
		)
		(fp_line
			(start 0.67945 -0.3048)
			(end 0.67945 0.3048)
			(stroke
				(width 0.1)
				(type default)
			)
			(layer "F.Fab")
		)
		(fp_line
			(start 0.67945 0.3048)
			(end 0.120396 0.3048)
			(stroke
				(width 0.1)
				(type default)
			)
			(layer "F.Fab")
		)
		(pad "1" smd circle
			(at -0.40005 0)
			(size 0 0)
			(layers "F.Cu" "F.Mask" "F.Paste")
			(net "P3V3_AUX")
		)
		(pad "2" smd circle
			(at 0.40005 0)
			(size 0 0)
			(layers "F.Cu" "F.Mask" "F.Paste")
			(net "GND")
		)
	)
)
